(kicad_pcb
	(version 20260206)
	(generator "pcbnew")
	(generator_version "10.0")
	(general
		(thickness 1.6)
		(legacy_teardrops no)
	)
	(paper "A4")
	(title_block
		(title "Bryce Canyon_IOM_M2_16342-2_OCP.brd")
		(comment 1 "Bryce Canyon / footprints 490-497 of 1146")
	)
	(layers
		(0 "F.Cu" signal "TOP")
		(4 "In1.Cu" signal "L2GND")
		(6 "In2.Cu" signal "L3")
		(8 "In3.Cu" signal "L4VCC")
		(10 "In4.Cu" signal "L5VCC")
		(12 "In5.Cu" signal "L6")
		(14 "In6.Cu" signal "L7GND")
		(2 "B.Cu" signal "BOTTOM")
		(9 "F.Adhes" user "F.Adhesive")
		(11 "B.Adhes" user "B.Adhesive")
		(13 "F.Paste" user "Package Geometry/Pastemask Top")
		(15 "B.Paste" user "Package Geometry/Pastemask Bottom")
		(5 "F.SilkS" user "Ref Des/Silkscreen Top")
		(7 "B.SilkS" user "Ref Des/Silkscreen Bottom")
		(1 "F.Mask" user "Board Geometry/Soldermask Top")
		(3 "B.Mask" user "Board Geometry/Soldermask Bottom")
		(17 "Dwgs.User" user "User.Drawings")
		(19 "Cmts.User" user "User.Comments")
		(21 "Eco1.User" user "User.Eco1")
		(23 "Eco2.User" user "User.Eco2")
		(25 "Edge.Cuts" user "Board Geometry/Outline")
		(27 "Margin" user)
		(31 "F.CrtYd" user "Package Geometry/Place Bound Top")
		(29 "B.CrtYd" user "Package Geometry/Place Bound Bottom")
		(35 "F.Fab" user "Ref Des/Assembly Top")
		(33 "B.Fab" user "Ref Des/Assembly Bottom")
	)
	(footprint ""
		(layer "F.Cu")
		(at 149.632416 -10.532618)
		(property "Reference" "C208"
			(at 0 0 0)
			(layer "F.SilkS")
			(hide yes)
			(effects
				(font
					(size 1.27 1.27)
				)
			)
		)
		(property "Value" "SC3300P50V2KX-1GP"
			(at 1.1811 -2.7051 0)
			(unlocked yes)
			(layer "F.Fab")
			(hide yes)
			(effects
				(font
					(size 1.016 1.016)
					(thickness 0.1524)
				)
			)
		)
		(property "Device Type" "C402H22"
			(at 1.1811 -4.2291 0)
			(unlocked yes)
			(layer "F.Fab")
			(hide yes)
			(effects
				(font
					(size 1.016 1.016)
					(thickness 0.1524)
				)
			)
		)
		(duplicate_pad_numbers_are_jumpers no)
		(fp_rect
			(start -0.4318 0.9525)
			(end 0.4318 -0.9525)
			(stroke
				(width 0)
				(type default)
			)
			(fill no)
			(layer "F.CrtYd")
		)
		(fp_rect
			(start -0.4318 0.9525)
			(end 0.4318 -0.9525)
			(stroke
				(width 0)
				(type default)
			)
			(fill no)
			(layer "F.Fab")
		)
		(pad "1" smd custom
			(at 0 -0.4445)
			(size 0.1524 0.1524)
			(layers "F.Cu" "F.Mask" "F.Paste")
			(net "P1V8_STBY_SS")
			(options
				(clearance outline)
				(anchor circle)
			)
			(primitives
				(gr_poly
					(pts
						(arc
							(start 0.3048 -0.2032)
							(mid 0.275042 -0.275042)
							(end 0.2032 -0.3048)
						)
						(arc
							(start -0.2032 -0.3048)
							(mid -0.275042 -0.275042)
							(end -0.3048 -0.2032)
						)
						(arc
							(start -0.3048 0.2032)
							(mid -0.275042 0.275042)
							(end -0.2032 0.3048)
						)
						(arc
							(start 0.2032 0.3048)
							(mid 0.275042 0.275042)
							(end 0.3048 0.2032)
						)
					)
					(width 0)
					(fill yes)
				)
			)
		)
		(pad "2" smd custom
			(at 0 0.4445)
			(size 0.1524 0.1524)
			(layers "F.Cu" "F.Mask" "F.Paste")
			(net "AGND_P1V8_STBY")
			(options
				(clearance outline)
				(anchor circle)
			)
			(primitives
				(gr_poly
					(pts
						(arc
							(start 0.3048 -0.2032)
							(mid 0.275042 -0.275042)
							(end 0.2032 -0.3048)
						)
						(arc
							(start -0.2032 -0.3048)
							(mid -0.275042 -0.275042)
							(end -0.3048 -0.2032)
						)
						(arc
							(start -0.3048 0.2032)
							(mid -0.275042 0.275042)
							(end -0.2032 0.3048)
						)
						(arc
							(start 0.2032 0.3048)
							(mid 0.275042 0.275042)
							(end 0.3048 0.2032)
						)
					)
					(width 0)
					(fill yes)
				)
			)
		)
	)
	(footprint ""
		(layer "F.Cu")
		(at 69.140324 -166.048182 -90)
		(property "Reference" "Q2"
			(at 0 0 270)
			(layer "F.SilkS")
			(hide yes)
			(effects
				(font
					(size 1.27 1.27)
				)
			)
		)
		(property "Value" "MMBT3904-3-GP"
			(at 0.10287 -10.29843 270)
			(unlocked yes)
			(layer "F.Fab")
			(hide yes)
			(effects
				(font
					(size 1.016 1.016)
					(thickness 0.1524)
				)
			)
		)
		(property "Device Type" "SOT23CBE2D4H44"
			(at 0.10287 -12.20343 270)
			(unlocked yes)
			(layer "F.Fab")
			(hide yes)
			(effects
				(font
					(size 1.016 1.016)
					(thickness 0.1524)
				)
			)
		)
		(duplicate_pad_numbers_are_jumpers no)
		(fp_line
			(start -1.651 1.778)
			(end 1.651 1.778)
			(stroke
				(width 0.1524)
				(type default)
			)
			(layer "F.SilkS")
		)
		(fp_line
			(start 1.651 1.778)
			(end 1.651 -1.778)
			(stroke
				(width 0.1524)
				(type default)
			)
			(layer "F.SilkS")
		)
		(fp_line
			(start -1.651 -1.778)
			(end -1.651 1.778)
			(stroke
				(width 0.1524)
				(type default)
			)
			(layer "F.SilkS")
		)
		(fp_line
			(start 1.651 -1.778)
			(end -1.651 -1.778)
			(stroke
				(width 0.1524)
				(type default)
			)
			(layer "F.SilkS")
		)
		(fp_poly
			(pts
				(xy -1.778 1.8796) (xy -1.778 -1.8796) (xy 1.778 -1.8796) (xy 1.778 1.8796)
			)
			(stroke
				(width 0)
				(type default)
			)
			(fill no)
			(layer "F.CrtYd")
		)
		(fp_poly
			(pts
				(xy -1.778 1.8796) (xy -1.778 -1.8796) (xy 1.778 -1.8796) (xy 1.778 1.8796)
			)
			(stroke
				(width 0)
				(type default)
			)
			(fill no)
			(layer "F.Fab")
		)
		(pad "B" smd custom
			(at -0.98425 0.9525 270)
			(size 0.1905 0.1905)
			(layers "F.Cu" "F.Mask" "F.Paste")
			(net "FM_TPM_PRSNT_RST")
			(options
				(clearance outline)
				(anchor circle)
			)
			(primitives
				(gr_poly
					(pts
						(arc
							(start -0.1778 0.5715)
							(mid -0.321484 0.511984)
							(end -0.381 0.3683)
						)
						(arc
							(start -0.381 -0.3683)
							(mid -0.321484 -0.511984)
							(end -0.1778 -0.5715)
						)
						(arc
							(start 0.1778 -0.5715)
							(mid 0.321484 -0.511984)
							(end 0.381 -0.3683)
						)
						(arc
							(start 0.381 0.3683)
							(mid 0.321484 0.511984)
							(end 0.1778 0.5715)
						)
					)
					(width 0)
					(fill yes)
				)
			)
		)
		(pad "C" smd custom
			(at 0 -0.9525 270)
			(size 0.1905 0.1905)
			(layers "F.Cu" "F.Mask" "F.Paste")
			(net "BMC_TPM_RST_N")
			(options
				(clearance outline)
				(anchor circle)
			)
			(primitives
				(gr_poly
					(pts
						(arc
							(start -0.1778 0.5715)
							(mid -0.321484 0.511984)
							(end -0.381 0.3683)
						)
						(arc
							(start -0.381 -0.3683)
							(mid -0.321484 -0.511984)
							(end -0.1778 -0.5715)
						)
						(arc
							(start 0.1778 -0.5715)
							(mid 0.321484 -0.511984)
							(end 0.381 -0.3683)
						)
						(arc
							(start 0.381 0.3683)
							(mid 0.321484 0.511984)
							(end 0.1778 0.5715)
						)
					)
					(width 0)
					(fill yes)
				)
			)
		)
		(pad "E" smd custom
			(at 0.98425 0.9525 270)
			(size 0.1905 0.1905)
			(layers "F.Cu" "F.Mask" "F.Paste")
			(net "GND")
			(options
				(clearance outline)
				(anchor circle)
			)
			(primitives
				(gr_poly
					(pts
						(arc
							(start -0.1778 0.5715)
							(mid -0.321484 0.511984)
							(end -0.381 0.3683)
						)
						(arc
							(start -0.381 -0.3683)
							(mid -0.321484 -0.511984)
							(end -0.1778 -0.5715)
						)
						(arc
							(start 0.1778 -0.5715)
							(mid 0.321484 -0.511984)
							(end 0.381 -0.3683)
						)
						(arc
							(start 0.381 0.3683)
							(mid 0.321484 0.511984)
							(end 0.1778 0.5715)
						)
					)
					(width 0)
					(fill yes)
				)
			)
		)
	)
	(footprint ""
		(layer "F.Cu")
		(at 110.758478 -10.791952 -90)
		(property "Reference" "C148"
			(at 0 0 270)
			(layer "F.SilkS")
			(hide yes)
			(effects
				(font
					(size 1.27 1.27)
				)
			)
		)
		(property "Value" "SCD1U50V3KX-GP"
			(at 0 -2.8194 270)
			(unlocked yes)
			(layer "F.Fab")
			(hide yes)
			(effects
				(font
					(size 1.016 1.016)
					(thickness 0.1524)
				)
			)
		)
		(property "Device Type" "C603H36"
			(at 0 -4.3434 270)
			(unlocked yes)
			(layer "F.Fab")
			(hide yes)
			(effects
				(font
					(size 1.016 1.016)
					(thickness 0.1524)
				)
			)
		)
		(duplicate_pad_numbers_are_jumpers no)
		(fp_line
			(start 0.508 0)
			(end -0.508 0)
			(stroke
				(width 0.2032)
				(type default)
			)
			(layer "F.SilkS")
		)
		(fp_rect
			(start -0.5842 1.3335)
			(end 0.5842 -1.3335)
			(stroke
				(width 0)
				(type default)
			)
			(fill no)
			(layer "F.CrtYd")
		)
		(fp_rect
			(start -0.5842 1.3335)
			(end 0.5842 -1.3335)
			(stroke
				(width 0)
				(type default)
			)
			(fill no)
			(layer "F.Fab")
		)
		(pad "1" smd custom
			(at 0 -0.762 270)
			(size 0.2159 0.2159)
			(layers "F.Cu" "F.Mask" "F.Paste")
			(net "MB0_ISET_R")
			(options
				(clearance outline)
				(anchor circle)
			)
			(primitives
				(gr_poly
					(pts
						(arc
							(start -0.3302 -0.4318)
							(mid -0.402042 -0.402042)
							(end -0.4318 -0.3302)
						)
						(arc
							(start -0.4318 0.3302)
							(mid -0.402042 0.402042)
							(end -0.3302 0.4318)
						)
						(arc
							(start 0.3302 0.4318)
							(mid 0.402042 0.402042)
							(end 0.4318 0.3302)
						)
						(arc
							(start 0.4318 -0.3302)
							(mid 0.402042 -0.402042)
							(end 0.3302 -0.4318)
						)
					)
					(width 0)
					(fill yes)
				)
			)
		)
		(pad "2" smd custom
			(at 0 0.762 270)
			(size 0.2159 0.2159)
			(layers "F.Cu" "F.Mask" "F.Paste")
			(net "AGND_CURRENT_MON")
			(options
				(clearance outline)
				(anchor circle)
			)
			(primitives
				(gr_poly
					(pts
						(arc
							(start -0.3302 -0.4318)
							(mid -0.402042 -0.402042)
							(end -0.4318 -0.3302)
						)
						(arc
							(start -0.4318 0.3302)
							(mid -0.402042 0.402042)
							(end -0.3302 0.4318)
						)
						(arc
							(start 0.3302 0.4318)
							(mid 0.402042 0.402042)
							(end 0.4318 0.3302)
						)
						(arc
							(start 0.4318 -0.3302)
							(mid 0.402042 -0.402042)
							(end 0.3302 -0.4318)
						)
					)
					(width 0)
					(fill yes)
				)
			)
		)
	)
	(footprint ""
		(layer "F.Cu")
		(at 55.152036 -132.360162)
		(property "Reference" "TP11"
			(at 0 0 0)
			(layer "F.SilkS")
			(hide yes)
			(effects
				(font
					(size 1.27 1.27)
				)
			)
		)
		(property "Value" "TPAD28-2-GP"
			(at -0.0127 -1.6637 0)
			(unlocked yes)
			(layer "F.Fab")
			(hide yes)
			(effects
				(font
					(size 1.016 1.016)
					(thickness 0.1524)
				)
			)
		)
		(property "Device Type" "TPAD28"
			(at -0.0127 -3.1877 0)
			(unlocked yes)
			(layer "F.Fab")
			(hide yes)
			(effects
				(font
					(size 1.016 1.016)
					(thickness 0.1524)
				)
			)
		)
		(duplicate_pad_numbers_are_jumpers no)
		(fp_poly
			(pts
				(arc
					(start 0.3556 0)
					(mid -0.3556 0)
					(end 0.3556 0)
				)
			)
			(stroke
				(width 0)
				(type default)
			)
			(fill no)
			(layer "F.CrtYd")
		)
		(fp_poly
			(pts
				(arc
					(start 0.6096 0)
					(mid -0.6096 0)
					(end 0.6096 0)
				)
			)
			(stroke
				(width 0)
				(type default)
			)
			(fill no)
			(layer "F.Fab")
		)
		(pad "1" smd circle
			(at 0 0)
			(size 0.7112 0.7112)
			(layers "F.Cu" "F.Mask" "F.Paste")
			(net "TP_BMC0_LPC_LAD2")
		)
	)
	(footprint ""
		(layer "F.Cu")
		(at 46.392592 -128.207516)
		(property "Reference" "R274"
			(at 0 0 0)
			(layer "F.SilkS")
			(hide yes)
			(effects
				(font
					(size 1.27 1.27)
				)
			)
		)
		(property "Value" "2K2R2F-GP"
			(at 0.064008 -3.993896 0)
			(unlocked yes)
			(layer "F.Fab")
			(hide yes)
			(effects
				(font
					(size 1.016 1.016)
					(thickness 0.1524)
				)
			)
		)
		(property "Device Type" "R402H16"
			(at 0.064008 -5.517896 0)
			(unlocked yes)
			(layer "F.Fab")
			(hide yes)
			(effects
				(font
					(size 1.016 1.016)
					(thickness 0.1524)
				)
			)
		)
		(duplicate_pad_numbers_are_jumpers no)
		(fp_line
			(start -0.508 -0.9398)
			(end -0.508 0.9398)
			(stroke
				(width 0.1524)
				(type default)
			)
			(layer "F.SilkS")
		)
		(fp_line
			(start 0.508 -0.9398)
			(end -0.508 -0.9398)
			(stroke
				(width 0.1524)
				(type default)
			)
			(layer "F.SilkS")
		)
		(fp_rect
			(start -0.508 0.9398)
			(end 0.508 -0.9398)
			(stroke
				(width 0)
				(type default)
			)
			(fill no)
			(layer "F.CrtYd")
		)
		(fp_rect
			(start -0.508 0.9398)
			(end 0.508 -0.9398)
			(stroke
				(width 0)
				(type default)
			)
			(fill no)
			(layer "F.Fab")
		)
		(pad "1" smd custom
			(at 0 -0.4445)
			(size 0.1397 0.1397)
			(layers "F.Cu" "F.Mask" "F.Paste")
			(net "BMC_SMB2_DAT")
			(options
				(clearance outline)
				(anchor circle)
			)
			(primitives
				(gr_poly
					(pts
						(arc
							(start -0.1778 -0.2794)
							(mid -0.249642 -0.249642)
							(end -0.2794 -0.1778)
						)
						(arc
							(start -0.2794 0.1778)
							(mid -0.249642 0.249642)
							(end -0.1778 0.2794)
						)
						(arc
							(start 0.1778 0.2794)
							(mid 0.249642 0.249642)
							(end 0.2794 0.1778)
						)
						(arc
							(start 0.2794 -0.1778)
							(mid 0.249642 -0.249642)
							(end 0.1778 -0.2794)
						)
					)
					(width 0)
					(fill yes)
				)
			)
		)
		(pad "2" smd custom
			(at 0 0.4445)
			(size 0.1397 0.1397)
			(layers "F.Cu" "F.Mask" "F.Paste")
			(net "P3V3_STBY")
			(options
				(clearance outline)
				(anchor circle)
			)
			(primitives
				(gr_poly
					(pts
						(arc
							(start -0.1778 -0.2794)
							(mid -0.249642 -0.249642)
							(end -0.2794 -0.1778)
						)
						(arc
							(start -0.2794 0.1778)
							(mid -0.249642 0.249642)
							(end -0.1778 0.2794)
						)
						(arc
							(start 0.1778 0.2794)
							(mid 0.249642 0.249642)
							(end 0.2794 0.1778)
						)
						(arc
							(start 0.2794 -0.1778)
							(mid 0.249642 -0.249642)
							(end 0.1778 -0.2794)
						)
					)
					(width 0)
					(fill yes)
				)
			)
		)
	)
	(footprint ""
		(layer "F.Cu")
		(at 48.05299 -158.5976)
		(property "Reference" "R170"
			(at 0 0 0)
			(layer "F.SilkS")
			(hide yes)
			(effects
				(font
					(size 1.27 1.27)
				)
			)
		)
		(property "Value" "0R2J-2-GP"
			(at 0.064008 -3.993896 0)
			(unlocked yes)
			(layer "F.Fab")
			(hide yes)
			(effects
				(font
					(size 1.016 1.016)
					(thickness 0.1524)
				)
			)
		)
		(property "Device Type" "R402H16"
			(at 0.064008 -5.517896 0)
			(unlocked yes)
			(layer "F.Fab")
			(hide yes)
			(effects
				(font
					(size 1.016 1.016)
					(thickness 0.1524)
				)
			)
		)
		(duplicate_pad_numbers_are_jumpers no)
		(fp_line
			(start -0.508 -0.9398)
			(end -0.508 0.9398)
			(stroke
				(width 0.1524)
				(type default)
			)
			(layer "F.SilkS")
		)
		(fp_line
			(start 0.508 -0.9398)
			(end -0.508 -0.9398)
			(stroke
				(width 0.1524)
				(type default)
			)
			(layer "F.SilkS")
		)
		(fp_rect
			(start -0.508 0.9398)
			(end 0.508 -0.9398)
			(stroke
				(width 0)
				(type default)
			)
			(fill no)
			(layer "F.CrtYd")
		)
		(fp_rect
			(start -0.508 0.9398)
			(end 0.508 -0.9398)
			(stroke
				(width 0)
				(type default)
			)
			(fill no)
			(layer "F.Fab")
		)
		(pad "1" smd custom
			(at 0 -0.4445)
			(size 0.1397 0.1397)
			(layers "F.Cu" "F.Mask" "F.Paste")
			(net "I2C_DPB_MISC_SDA_OUT")
			(options
				(clearance outline)
				(anchor circle)
			)
			(primitives
				(gr_poly
					(pts
						(arc
							(start -0.1778 -0.2794)
							(mid -0.249642 -0.249642)
							(end -0.2794 -0.1778)
						)
						(arc
							(start -0.2794 0.1778)
							(mid -0.249642 0.249642)
							(end -0.1778 0.2794)
						)
						(arc
							(start 0.1778 0.2794)
							(mid 0.249642 0.249642)
							(end 0.2794 0.1778)
						)
						(arc
							(start 0.2794 -0.1778)
							(mid 0.249642 -0.249642)
							(end 0.1778 -0.2794)
						)
					)
					(width 0)
					(fill yes)
				)
			)
		)
		(pad "2" smd custom
			(at 0 0.4445)
			(size 0.1397 0.1397)
			(layers "F.Cu" "F.Mask" "F.Paste")
			(net "BMC_SMB6_DAT")
			(options
				(clearance outline)
				(anchor circle)
			)
			(primitives
				(gr_poly
					(pts
						(arc
							(start -0.1778 -0.2794)
							(mid -0.249642 -0.249642)
							(end -0.2794 -0.1778)
						)
						(arc
							(start -0.2794 0.1778)
							(mid -0.249642 0.249642)
							(end -0.1778 0.2794)
						)
						(arc
							(start 0.1778 0.2794)
							(mid 0.249642 0.249642)
							(end 0.2794 0.1778)
						)
						(arc
							(start 0.2794 -0.1778)
							(mid 0.249642 -0.249642)
							(end 0.1778 -0.2794)
						)
					)
					(width 0)
					(fill yes)
				)
			)
		)
	)
	(footprint ""
		(layer "F.Cu")
		(at 97.6122 -177.292 90)
		(property "Reference" "C141"
			(at 0 0 90)
			(layer "F.SilkS")
			(hide yes)
			(effects
				(font
					(size 1.27 1.27)
				)
			)
		)
		(property "Value" "SCD1U16V2KX-3GP"
			(at 1.1811 -2.7051 90)
			(unlocked yes)
			(layer "F.Fab")
			(hide yes)
			(effects
				(font
					(size 1.016 1.016)
					(thickness 0.1524)
				)
			)
		)
		(property "Device Type" "C402H22"
			(at 1.1811 -4.2291 90)
			(unlocked yes)
			(layer "F.Fab")
			(hide yes)
			(effects
				(font
					(size 1.016 1.016)
					(thickness 0.1524)
				)
			)
		)
		(duplicate_pad_numbers_are_jumpers no)
		(fp_rect
			(start -0.4318 0.9525)
			(end 0.4318 -0.9525)
			(stroke
				(width 0)
				(type default)
			)
			(fill no)
			(layer "F.CrtYd")
		)
		(fp_rect
			(start -0.4318 0.9525)
			(end 0.4318 -0.9525)
			(stroke
				(width 0)
				(type default)
			)
			(fill no)
			(layer "F.Fab")
		)
		(pad "1" smd custom
			(at 0 -0.4445 90)
			(size 0.1524 0.1524)
			(layers "F.Cu" "F.Mask" "F.Paste")
			(net "P3V3_STBY")
			(options
				(clearance outline)
				(anchor circle)
			)
			(primitives
				(gr_poly
					(pts
						(arc
							(start 0.3048 -0.2032)
							(mid 0.275042 -0.275042)
							(end 0.2032 -0.3048)
						)
						(arc
							(start -0.2032 -0.3048)
							(mid -0.275042 -0.275042)
							(end -0.3048 -0.2032)
						)
						(arc
							(start -0.3048 0.2032)
							(mid -0.275042 0.275042)
							(end -0.2032 0.3048)
						)
						(arc
							(start 0.2032 0.3048)
							(mid 0.275042 0.275042)
							(end 0.3048 0.2032)
						)
					)
					(width 0)
					(fill yes)
				)
			)
		)
		(pad "2" smd custom
			(at 0 0.4445 90)
			(size 0.1524 0.1524)
			(layers "F.Cu" "F.Mask" "F.Paste")
			(net "GND")
			(options
				(clearance outline)
				(anchor circle)
			)
			(primitives
				(gr_poly
					(pts
						(arc
							(start 0.3048 -0.2032)
							(mid 0.275042 -0.275042)
							(end 0.2032 -0.3048)
						)
						(arc
							(start -0.2032 -0.3048)
							(mid -0.275042 -0.275042)
							(end -0.3048 -0.2032)
						)
						(arc
							(start -0.3048 0.2032)
							(mid -0.275042 0.275042)
							(end -0.2032 0.3048)
						)
						(arc
							(start 0.2032 0.3048)
							(mid 0.275042 0.275042)
							(end 0.3048 0.2032)
						)
					)
					(width 0)
					(fill yes)
				)
			)
		)
	)
	(footprint ""
		(layer "F.Cu")
		(at 34.544 -159.2834)
		(property "Reference" "C91"
			(at 0 0 0)
			(layer "F.SilkS")
			(hide yes)
			(effects
				(font
					(size 1.27 1.27)
				)
			)
		)
		(property "Value" "SC100P50V2JN-3GP"
			(at 1.1811 -2.7051 0)
			(unlocked yes)
			(layer "F.Fab")
			(hide yes)
			(effects
				(font
					(size 1.016 1.016)
					(thickness 0.1524)
				)
			)
		)
		(property "Device Type" "C402H22"
			(at 1.1811 -4.2291 0)
			(unlocked yes)
			(layer "F.Fab")
			(hide yes)
			(effects
				(font
					(size 1.016 1.016)
					(thickness 0.1524)
				)
			)
		)
		(duplicate_pad_numbers_are_jumpers no)
		(fp_rect
			(start -0.4318 0.9525)
			(end 0.4318 -0.9525)
			(stroke
				(width 0)
				(type default)
			)
			(fill no)
			(layer "F.CrtYd")
		)
		(fp_rect
			(start -0.4318 0.9525)
			(end 0.4318 -0.9525)
			(stroke
				(width 0)
				(type default)
			)
			(fill no)
			(layer "F.Fab")
		)
		(pad "1" smd custom
			(at 0 -0.4445)
			(size 0.1524 0.1524)
			(layers "F.Cu" "F.Mask" "F.Paste")
			(net "DACAV33")
			(options
				(clearance outline)
				(anchor circle)
			)
			(primitives
				(gr_poly
					(pts
						(arc
							(start 0.3048 -0.2032)
							(mid 0.275042 -0.275042)
							(end 0.2032 -0.3048)
						)
						(arc
							(start -0.2032 -0.3048)
							(mid -0.275042 -0.275042)
							(end -0.3048 -0.2032)
						)
						(arc
							(start -0.3048 0.2032)
							(mid -0.275042 0.275042)
							(end -0.2032 0.3048)
						)
						(arc
							(start 0.2032 0.3048)
							(mid 0.275042 0.275042)
							(end 0.3048 0.2032)
						)
					)
					(width 0)
					(fill yes)
				)
			)
		)
		(pad "2" smd custom
			(at 0 0.4445)
			(size 0.1524 0.1524)
			(layers "F.Cu" "F.Mask" "F.Paste")
			(net "GND")
			(options
				(clearance outline)
				(anchor circle)
			)
			(primitives
				(gr_poly
					(pts
						(arc
							(start 0.3048 -0.2032)
							(mid 0.275042 -0.275042)
							(end 0.2032 -0.3048)
						)
						(arc
							(start -0.2032 -0.3048)
							(mid -0.275042 -0.275042)
							(end -0.3048 -0.2032)
						)
						(arc
							(start -0.3048 0.2032)
							(mid -0.275042 0.275042)
							(end -0.2032 0.3048)
						)
						(arc
							(start 0.2032 0.3048)
							(mid 0.275042 0.275042)
							(end 0.3048 0.2032)
						)
					)
					(width 0)
					(fill yes)
				)
			)
		)
	)
)
